# T6G (Grand Teton) — schematic netlist excerpt (pin names and nets, part order shuffled) for the footprints in the layout excerpt that follows; sources: Cadence DE-HDL packaged netlist, KiCad conversion of 04192023_DAF0TMB3IC0_F0TG_MB_C_brd_V02_OCP.brd

R8107  Q_RES  10K 1% EMPTY  pkg 0402LF  page 267 : A = P3V3_AUX ; B = OC_P2V5_COMP
PC149_6  Q_CAP  22UF 4V 20% X6S  pkg C0805  page 220 : A = PVDDCR_CPU1_P1 ; B = GND

(kicad_pcb
	(version 20260206)
	(generator "pcbnew")
	(generator_version "10.0")
	(general
		(thickness 1.6)
		(legacy_teardrops no)
	)
	(paper "A4")
	(title_block
		(title "04192023_DAF0TMB3IC0_F0TG_MB_C_brd_V02_OCP.brd")
		(comment 1 "Grand Teton / footprints 5355-5356 of 8354")
	)
	(layers
		(0 "F.Cu" signal "TOP")
		(4 "In1.Cu" signal "GND")
		(6 "In2.Cu" signal "IN1")
		(8 "In3.Cu" signal "GND1")
		(10 "In4.Cu" signal "IN2")
		(12 "In5.Cu" signal "GND2")
		(14 "In6.Cu" signal "IN3")
		(16 "In7.Cu" signal "GND3")
		(18 "In8.Cu" signal "VCC")
		(20 "In9.Cu" signal "VCC1")
		(22 "In10.Cu" signal "GND4")
		(24 "In11.Cu" signal "IN4")
		(26 "In12.Cu" signal "GND5")
		(28 "In13.Cu" signal "IN5")
		(30 "In14.Cu" signal "GND6")
		(32 "In15.Cu" signal "IN6")
		(34 "In16.Cu" signal "GND7")
		(2 "B.Cu" signal "BOTTOM")
		(9 "F.Adhes" user "F.Adhesive")
		(11 "B.Adhes" user "B.Adhesive")
		(13 "F.Paste" user "Package Geometry/Pastemask Top")
		(15 "B.Paste" user "Package Geometry/Pastemask Bottom")
		(5 "F.SilkS" user "Ref Des/Silkscreen Top")
		(7 "B.SilkS" user "Ref Des/Silkscreen Bottom")
		(1 "F.Mask" user "Board Geometry/Soldermask Top")
		(3 "B.Mask" user "Board Geometry/Soldermask Bottom")
		(17 "Dwgs.User" user "User.Drawings")
		(19 "Cmts.User" user "User.Comments")
		(21 "Eco1.User" user "User.Eco1")
		(23 "Eco2.User" user "User.Eco2")
		(25 "Edge.Cuts" user "Board Geometry/Outline")
		(27 "Margin" user)
		(31 "F.CrtYd" user "Package Geometry/Place Bound Top")
		(29 "B.CrtYd" user "Package Geometry/Place Bound Bottom")
		(35 "F.Fab" user "Ref Des/Assembly Top")
		(33 "B.Fab" user "Ref Des/Assembly Bottom")
	)
	(footprint ""
		(layer "B.Cu")
		(at 100.628704 -331.279754 -90)
		(property "Reference" "PC149_6"
			(at 0 0 90)
			(layer "B.SilkS")
			(hide yes)
			(effects
				(font
					(size 1.27 1.27)
				)
				(justify mirror)
			)
		)
		(property "Value" ""
			(at 0 0 90)
			(layer "B.Fab")
			(effects
				(font
					(size 1.27 1.27)
				)
				(justify mirror)
			)
		)
		(duplicate_pad_numbers_are_jumpers no)
		(fp_line
			(start -1.524 0.762)
			(end 1.524 0.762)
			(stroke
				(width 0.1524)
				(type default)
			)
			(layer "B.SilkS")
		)
		(fp_line
			(start 1.524 0.762)
			(end 1.524 -0.762)
			(stroke
				(width 0.1524)
				(type default)
			)
			(layer "B.SilkS")
		)
		(fp_line
			(start -1.524 -0.762)
			(end -1.524 0.762)
			(stroke
				(width 0.1524)
				(type default)
			)
			(layer "B.SilkS")
		)
		(fp_line
			(start 1.524 -0.762)
			(end -1.524 -0.762)
			(stroke
				(width 0.1524)
				(type default)
			)
			(layer "B.SilkS")
		)
		(fp_line
			(start -1.1049 0.724916)
			(end -1.1049 -0.724916)
			(stroke
				(width 0.1)
				(type default)
			)
			(layer "B.Fab")
		)
		(fp_line
			(start 1.1049 0.724916)
			(end -1.1049 0.724916)
			(stroke
				(width 0.1)
				(type default)
			)
			(layer "B.Fab")
		)
		(fp_line
			(start -1.1049 -0.724916)
			(end 1.1049 -0.724916)
			(stroke
				(width 0.1)
				(type default)
			)
			(layer "B.Fab")
		)
		(fp_line
			(start 1.1049 -0.724916)
			(end 1.1049 0.724916)
			(stroke
				(width 0.1)
				(type default)
			)
			(layer "B.Fab")
		)
		(pad "1" smd rect
			(at 0.889 0 270)
			(size 1.016 1.27)
			(layers "B.Cu" "B.Mask" "B.Paste")
			(net "PVDDCR_CPU1_P1")
		)
		(pad "2" smd rect
			(at -0.889 0 270)
			(size 1.016 1.27)
			(layers "B.Cu" "B.Mask" "B.Paste")
			(net "GND")
		)
	)
	(footprint ""
		(layer "B.Cu")
		(at 188.849 -422.402)
		(property "Reference" "R8107"
			(at 0 0 0)
			(layer "B.SilkS")
			(hide yes)
			(effects
				(font
					(size 1.27 1.27)
				)
				(justify mirror)
			)
		)
		(property "Value" ""
			(at 0 0 0)
			(layer "B.Fab")
			(effects
				(font
					(size 1.27 1.27)
				)
				(justify mirror)
			)
		)
		(duplicate_pad_numbers_are_jumpers no)
		(fp_line
			(start -0.7874 -0.4064)
			(end -0.7874 0.4064)
			(stroke
				(width 0.1524)
				(type default)
			)
			(layer "B.SilkS")
		)
		(fp_line
			(start -0.7874 0.4064)
			(end 0.7874 0.4064)
			(stroke
				(width 0.1524)
				(type default)
			)
			(layer "B.SilkS")
		)
		(fp_line
			(start 0.7874 -0.4064)
			(end -0.7874 -0.4064)
			(stroke
				(width 0.1524)
				(type default)
			)
			(layer "B.SilkS")
		)
		(fp_line
			(start 0.7874 0.4064)
			(end 0.7874 -0.4064)
			(stroke
				(width 0.1524)
				(type default)
			)
			(layer "B.SilkS")
		)
		(fp_line
			(start -0.67945 -0.3048)
			(end -0.67945 0.3048)
			(stroke
				(width 0.1)
				(type default)
			)
			(layer "B.Fab")
		)
		(fp_line
			(start -0.67945 0.3048)
			(end -0.120396 0.3048)
			(stroke
				(width 0.1)
				(type default)
			)
			(layer "B.Fab")
		)
		(fp_line
			(start -0.12065 -0.3048)
			(end -0.67945 -0.3048)
			(stroke
				(width 0.1)
				(type default)
			)
			(layer "B.Fab")
		)
		(fp_line
			(start -0.12065 -0.2794)
			(end -0.12065 -0.3048)
			(stroke
				(width 0.1)
				(type default)
			)
			(layer "B.Fab")
		)
		(fp_line
			(start -0.120396 0.2794)
			(end 0.12065 0.2794)
			(stroke
				(width 0.1)
				(type default)
			)
			(layer "B.Fab")
		)
		(fp_line
			(start -0.120396 0.3048)
			(end -0.120396 0.2794)
			(stroke
				(width 0.1)
				(type default)
			)
			(layer "B.Fab")
		)
		(fp_line
			(start 0.12065 -0.305054)
			(end 0.12065 -0.2794)
			(stroke
				(width 0.1)
				(type default)
			)
			(layer "B.Fab")
		)
		(fp_line
			(start 0.12065 -0.2794)
			(end -0.12065 -0.2794)
			(stroke
				(width 0.1)
				(type default)
			)
			(layer "B.Fab")
		)
		(fp_line
			(start 0.12065 0.2794)
			(end 0.12065 0.3048)
			(stroke
				(width 0.1)
				(type default)
			)
			(layer "B.Fab")
		)
		(fp_line
			(start 0.12065 0.3048)
			(end 0.67945 0.3048)
			(stroke
				(width 0.1)
				(type default)
			)
			(layer "B.Fab")
		)
		(fp_line
			(start 0.67945 -0.305054)
			(end 0.12065 -0.305054)
			(stroke
				(width 0.1)
				(type default)
			)
			(layer "B.Fab")
		)
		(fp_line
			(start 0.67945 0.3048)
			(end 0.67945 -0.305054)
			(stroke
				(width 0.1)
				(type default)
			)
			(layer "B.Fab")
		)
		(pad "1" smd circle
			(at 0.40005 0 180)
			(size 0 0)
			(layers "B.Cu" "B.Mask" "B.Paste")
			(net "P3V3_AUX")
		)
		(pad "2" smd circle
			(at -0.40005 0 180)
			(size 0 0)
			(layers "B.Cu" "B.Mask" "B.Paste")
			(net "OC_P2V5_COMP")
		)
	)
)
